(kicad_pcb
	(version 20241229)
	(generator "pcbnew")
	(generator_version "9.0")
	(general
		(thickness 1.61)
		(legacy_teardrops no)
	)
	(paper "A3")
	(title_block
		(title "SO-DIMM DDR5 Tester")
		(date "2025-11-26")
		(rev "1.3.0")
		(comment 9 "footprints 498-503 of 627")
	)
	(layers
		(0 "F.Cu" signal)
		(4 "In1.Cu" power)
		(6 "In2.Cu" mixed)
		(8 "In3.Cu" power)
		(10 "In4.Cu" mixed)
		(12 "In5.Cu" power)
		(14 "In6.Cu" mixed)
		(16 "In7.Cu" power)
		(18 "In8.Cu" power)
		(20 "In9.Cu" mixed)
		(22 "In10.Cu" power)
		(2 "B.Cu" signal)
		(9 "F.Adhes" user "F.Adhesive")
		(11 "B.Adhes" user "B.Adhesive")
		(13 "F.Paste" user)
		(15 "B.Paste" user)
		(5 "F.SilkS" user "F.Silkscreen")
		(7 "B.SilkS" user "B.Silkscreen")
		(1 "F.Mask" user)
		(3 "B.Mask" user)
		(17 "Dwgs.User" user "User.Drawings")
		(19 "Cmts.User" user "User.Comments")
		(21 "Eco1.User" user "User.Eco1")
		(23 "Eco2.User" user "User.Eco2")
		(25 "Edge.Cuts" user)
		(27 "Margin" user)
		(31 "F.CrtYd" user "F.Courtyard")
		(29 "B.CrtYd" user "B.Courtyard")
		(35 "F.Fab" user)
		(33 "B.Fab" user)
	)
	(footprint "antmicro-footprints:C_0402_1005Metric"
		(layer "B.Cu")
		(at 202.95 185.35 -90)
		(descr "Capacitor SMD 0402")
		(tags "capacitor SMD 0402")
		(property "Reference" "C172"
			(at 0 0.699 90)
			(layer "B.SilkS")
			(hide yes)
			(effects
				(font
					(size 0.7 0.7)
					(thickness 0.15)
				)
				(justify left bottom mirror)
			)
		)
		(property "Value" "C_1u_0402"
			(at -1.022927 -2.155213 90)
			(layer "B.Fab")
			(effects
				(font
					(size 0.7 0.7)
					(thickness 0.15)
				)
				(justify left bottom mirror)
			)
		)
		(property "Datasheet" "https://product.tdk.com/en/search/capacitor/ceramic/mlcc/info?part_no=C1005X6S1A105K050BC"
			(at 0 0 270)
			(layer "F.Fab")
			(hide yes)
			(effects
				(font
					(size 1.27 1.27)
					(thickness 0.15)
				)
			)
		)
		(property "Author" "Antmicro"
			(at 17.6 388.3 0)
			(layer "B.Fab")
			(hide yes)
			(effects
				(font
					(size 1 1)
					(thickness 0.15)
				)
				(justify mirror)
			)
		)
		(property "Dielectric" ""
			(at 17.6 388.3 0)
			(layer "B.Fab")
			(hide yes)
			(effects
				(font
					(size 1 1)
					(thickness 0.15)
				)
				(justify mirror)
			)
		)
		(property "License" "Apache-2.0"
			(at 17.6 388.3 0)
			(layer "B.Fab")
			(hide yes)
			(effects
				(font
					(size 1 1)
					(thickness 0.15)
				)
				(justify mirror)
			)
		)
		(property "MPN" "C1005X6S1A105K050BC"
			(at 17.6 388.3 0)
			(layer "B.Fab")
			(hide yes)
			(effects
				(font
					(size 1 1)
					(thickness 0.15)
				)
				(justify mirror)
			)
		)
		(property "Manufacturer" "TDK"
			(at 17.6 388.3 0)
			(layer "B.Fab")
			(hide yes)
			(effects
				(font
					(size 1 1)
					(thickness 0.15)
				)
				(justify mirror)
			)
		)
		(property "Val" "1u"
			(at 17.6 388.3 0)
			(layer "B.Fab")
			(hide yes)
			(effects
				(font
					(size 1 1)
					(thickness 0.15)
				)
				(justify mirror)
			)
		)
		(property "Voltage" ""
			(at 17.6 388.3 0)
			(layer "B.Fab")
			(hide yes)
			(effects
				(font
					(size 1 1)
					(thickness 0.15)
				)
				(justify mirror)
			)
		)
		(sheetname "/Supply/")
		(sheetfile "supply.kicad_sch")
		(attr smd)
		(fp_rect
			(start -0.9659 0.481258)
			(end 0.9649 -0.458742)
			(stroke
				(width 0.05)
				(type solid)
			)
			(fill no)
			(layer "B.CrtYd")
		)
		(fp_line
			(start -0.499 0.25)
			(end 0.499 0.25)
			(stroke
				(width 0.15)
				(type solid)
			)
			(layer "B.Fab")
		)
		(fp_line
			(start 0.499 0.25)
			(end 0.499 -0.248)
			(stroke
				(width 0.15)
				(type solid)
			)
			(layer "B.Fab")
		)
		(fp_line
			(start -0.499 -0.248)
			(end -0.499 0.25)
			(stroke
				(width 0.15)
				(type solid)
			)
			(layer "B.Fab")
		)
		(fp_line
			(start 0.499 -0.248)
			(end -0.499 -0.248)
			(stroke
				(width 0.15)
				(type solid)
			)
			(layer "B.Fab")
		)
		(pad "1" smd roundrect
			(at -0.484 0 270)
			(size 0.59 0.64)
			(layers "B.Cu" "B.Mask" "B.Paste")
			(roundrect_rratio 0.25)
			(net 1 "GND")
			(pintype "passive")
		)
		(pad "2" smd roundrect
			(at 0.484 0 270)
			(size 0.59 0.64)
			(layers "B.Cu" "B.Mask" "B.Paste")
			(roundrect_rratio 0.25)
			(net 39 "/Supply/QDCDC1_VCC")
			(pintype "passive")
		)
	)
	(footprint "antmicro-footprints:C_0402_1005Metric"
		(layer "B.Cu")
		(at 140.525501 204.850501 90)
		(descr "Capacitor SMD 0402")
		(tags "capacitor SMD 0402")
		(property "Reference" "C227"
			(at 0 0.699 270)
			(layer "B.SilkS")
			(hide yes)
			(effects
				(font
					(size 0.7 0.7)
					(thickness 0.15)
				)
				(justify left bottom mirror)
			)
		)
		(property "Value" "C_100n_0402"
			(at -1.022927 -2.155213 270)
			(layer "B.Fab")
			(effects
				(font
					(size 0.7 0.7)
					(thickness 0.15)
				)
				(justify left bottom mirror)
			)
		)
		(property "Datasheet" "https://www.murata.com/products/productdetail?partno=GRM155R61H104KE14%23"
			(at 0 0 90)
			(layer "F.Fab")
			(hide yes)
			(effects
				(font
					(size 1.27 1.27)
					(thickness 0.15)
				)
			)
		)
		(property "Author" "Antmicro"
			(at 345.376002 64.325 0)
			(layer "B.Fab")
			(hide yes)
			(effects
				(font
					(size 1 1)
					(thickness 0.15)
				)
				(justify mirror)
			)
		)
		(property "Dielectric" "X5R"
			(at 345.376002 64.325 0)
			(layer "B.Fab")
			(hide yes)
			(effects
				(font
					(size 1 1)
					(thickness 0.15)
				)
				(justify mirror)
			)
		)
		(property "License" "Apache-2.0"
			(at 345.376002 64.325 0)
			(layer "B.Fab")
			(hide yes)
			(effects
				(font
					(size 1 1)
					(thickness 0.15)
				)
				(justify mirror)
			)
		)
		(property "MPN" "GRM155R61H104KE14D"
			(at 345.376002 64.325 0)
			(layer "B.Fab")
			(hide yes)
			(effects
				(font
					(size 1 1)
					(thickness 0.15)
				)
				(justify mirror)
			)
		)
		(property "Manufacturer" "Murata"
			(at 345.376002 64.325 0)
			(layer "B.Fab")
			(hide yes)
			(effects
				(font
					(size 1 1)
					(thickness 0.15)
				)
				(justify mirror)
			)
		)
		(property "Val" "100n"
			(at 345.376002 64.325 0)
			(layer "B.Fab")
			(hide yes)
			(effects
				(font
					(size 1 1)
					(thickness 0.15)
				)
				(justify mirror)
			)
		)
		(property "Voltage" "50V"
			(at 345.376002 64.325 0)
			(layer "B.Fab")
			(hide yes)
			(effects
				(font
					(size 1 1)
					(thickness 0.15)
				)
				(justify mirror)
			)
		)
		(sheetname "/FPGA MGT Interface/")
		(sheetfile "fpga-mgt.kicad_sch")
		(attr smd)
		(fp_rect
			(start -0.9659 0.481258)
			(end 0.9649 -0.458742)
			(stroke
				(width 0.05)
				(type solid)
			)
			(fill no)
			(layer "B.CrtYd")
		)
		(fp_line
			(start 0.499 -0.248)
			(end -0.499 -0.248)
			(stroke
				(width 0.15)
				(type solid)
			)
			(layer "B.Fab")
		)
		(fp_line
			(start -0.499 -0.248)
			(end -0.499 0.25)
			(stroke
				(width 0.15)
				(type solid)
			)
			(layer "B.Fab")
		)
		(fp_line
			(start 0.499 0.25)
			(end 0.499 -0.248)
			(stroke
				(width 0.15)
				(type solid)
			)
			(layer "B.Fab")
		)
		(fp_line
			(start -0.499 0.25)
			(end 0.499 0.25)
			(stroke
				(width 0.15)
				(type solid)
			)
			(layer "B.Fab")
		)
		(pad "1" smd roundrect
			(at -0.484 0 90)
			(size 0.59 0.64)
			(layers "B.Cu" "B.Mask" "B.Paste")
			(roundrect_rratio 0.25)
			(net 18 "/FPGA MGT Interface/PCIE.TXD2_P")
			(pintype "passive")
		)
		(pad "2" smd roundrect
			(at 0.484 0 90)
			(size 0.59 0.64)
			(layers "B.Cu" "B.Mask" "B.Paste")
			(roundrect_rratio 0.25)
			(net 19 "/FPGA MGT Interface/GTX_TX1_P")
			(pintype "passive")
		)
	)
	(footprint "antmicro-footprints:R_0402_1005Metric"
		(layer "B.Cu")
		(at 196.7 179.4 180)
		(descr "Resistor SMD 0402")
		(tags "resistor SMD 0402")
		(property "Reference" "R154"
			(at -3.8 -0.35 0)
			(layer "B.SilkS")
			(effects
				(font
					(size 0.7 0.7)
					(thickness 0.15)
				)
				(justify left bottom mirror)
			)
		)
		(property "Value" "R_0R_0402"
			(at -1.011843 -1.772047 0)
			(layer "B.Fab")
			(effects
				(font
					(size 0.7 0.7)
					(thickness 0.15)
				)
				(justify left bottom mirror)
			)
		)
		(property "Datasheet" "https://industrial.panasonic.com/cdbs/www-data/pdf/RDA0000/AOA0000C301.pdf"
			(at 0 0 180)
			(layer "F.Fab")
			(hide yes)
			(effects
				(font
					(size 1.27 1.27)
					(thickness 0.15)
				)
			)
		)
		(property "Author" "Antmicro"
			(at 393.4 358.8 0)
			(layer "B.Fab")
			(hide yes)
			(effects
				(font
					(size 1 1)
					(thickness 0.15)
				)
				(justify mirror)
			)
		)
		(property "Current" "1A"
			(at 393.4 358.8 0)
			(layer "B.Fab")
			(hide yes)
			(effects
				(font
					(size 1 1)
					(thickness 0.15)
				)
				(justify mirror)
			)
		)
		(property "License" "Apache-2.0"
			(at 393.4 358.8 0)
			(layer "B.Fab")
			(hide yes)
			(effects
				(font
					(size 1 1)
					(thickness 0.15)
				)
				(justify mirror)
			)
		)
		(property "MPN" "ERJ2GE0R00X"
			(at 393.4 358.8 0)
			(layer "B.Fab")
			(hide yes)
			(effects
				(font
					(size 1 1)
					(thickness 0.15)
				)
				(justify mirror)
			)
		)
		(property "Manufacturer" "Panasonic"
			(at 393.4 358.8 0)
			(layer "B.Fab")
			(hide yes)
			(effects
				(font
					(size 1 1)
					(thickness 0.15)
				)
				(justify mirror)
			)
		)
		(property "Tolerance" ""
			(at 393.4 358.8 0)
			(layer "B.Fab")
			(hide yes)
			(effects
				(font
					(size 1 1)
					(thickness 0.15)
				)
				(justify mirror)
			)
		)
		(property "Val" "0R"
			(at 393.4 358.8 0)
			(layer "B.Fab")
			(hide yes)
			(effects
				(font
					(size 1 1)
					(thickness 0.15)
				)
				(justify mirror)
			)
		)
		(sheetname "/Supply/")
		(sheetfile "supply.kicad_sch")
		(attr exclude_from_pos_files exclude_from_bom dnp)
		(fp_rect
			(start -0.93 0.47)
			(end 0.93 -0.47)
			(stroke
				(width 0.05)
				(type solid)
			)
			(fill no)
			(layer "B.CrtYd")
		)
		(fp_rect
			(start -0.5 0.25)
			(end 0.5 -0.25)
			(stroke
				(width 0.15)
				(type solid)
			)
			(fill no)
			(layer "B.Fab")
		)
		(pad "1" smd roundrect
			(at -0.485 0 180)
			(size 0.59 0.64)
			(layers "B.Cu" "B.Mask" "B.Paste")
			(roundrect_rratio 0.25)
			(net 1 "GND")
			(pintype "passive")
		)
		(pad "2" smd roundrect
			(at 0.485 0 180)
			(size 0.59 0.64)
			(layers "B.Cu" "B.Mask" "B.Paste")
			(roundrect_rratio 0.25)
			(net 211 "/Supply/FB2")
			(pintype "passive")
		)
	)
	(footprint "antmicro-footprints:C_0402_1005Metric"
		(layer "B.Cu")
		(at 142.875001 176.3025)
		(descr "Capacitor SMD 0402 (1005 Metric), square (rectangular) end terminal, IPC_7351 nominal, (Body size source: IPC-SM-782 page 76, https://www.pcb-3d.com/wordpress/wp-content/uploads/ipc-sm-782a_amendment_1_and_2.pdf)")
		(tags "capacitor 0402")
		(property "Reference" "C48"
			(at 0 1.17 180)
			(layer "B.SilkS")
			(hide yes)
			(effects
				(font
					(size 0.7 0.7)
					(thickness 0.15)
				)
				(justify left bottom mirror)
			)
		)
		(property "Value" "C_100n_0402"
			(at 0 -1.169 180)
			(layer "B.Fab")
			(effects
				(font
					(size 0.7 0.7)
					(thickness 0.15)
				)
				(justify left bottom mirror)
			)
		)
		(property "Datasheet" "https://www.murata.com/products/productdetail?partno=GRM155R61H104KE14%23"
			(at 0 0 0)
			(layer "F.Fab")
			(hide yes)
			(effects
				(font
					(size 1.27 1.27)
					(thickness 0.15)
				)
			)
		)
		(property "Author" "Antmicro"
			(at 0 0 0)
			(layer "B.Fab")
			(hide yes)
			(effects
				(font
					(size 1 1)
					(thickness 0.15)
				)
				(justify mirror)
			)
		)
		(property "Dielectric" "X5R"
			(at 0 0 0)
			(layer "B.Fab")
			(hide yes)
			(effects
				(font
					(size 1 1)
					(thickness 0.15)
				)
				(justify mirror)
			)
		)
		(property "License" "Apache-2.0"
			(at 0 0 0)
			(layer "B.Fab")
			(hide yes)
			(effects
				(font
					(size 1 1)
					(thickness 0.15)
				)
				(justify mirror)
			)
		)
		(property "MPN" "GRM155R61H104KE14D"
			(at 0 0 0)
			(layer "B.Fab")
			(hide yes)
			(effects
				(font
					(size 1 1)
					(thickness 0.15)
				)
				(justify mirror)
			)
		)
		(property "Manufacturer" "Murata"
			(at 0 0 0)
			(layer "B.Fab")
			(hide yes)
			(effects
				(font
					(size 1 1)
					(thickness 0.15)
				)
				(justify mirror)
			)
		)
		(property "Val" "100n"
			(at 0 0 0)
			(layer "B.Fab")
			(hide yes)
			(effects
				(font
					(size 1 1)
					(thickness 0.15)
				)
				(justify mirror)
			)
		)
		(property "Voltage" "50V"
			(at 0 0 0)
			(layer "B.Fab")
			(hide yes)
			(effects
				(font
					(size 1 1)
					(thickness 0.15)
				)
				(justify mirror)
			)
		)
		(sheetname "/FPGA power/")
		(sheetfile "fpga-power.kicad_sch")
		(attr smd)
		(fp_rect
			(start -0.9656 0.4572)
			(end 0.9652 -0.4828)
			(stroke
				(width 0.05)
				(type solid)
			)
			(fill no)
			(layer "B.CrtYd")
		)
		(fp_line
			(start -0.5 -0.248)
			(end -0.5 0.25)
			(stroke
				(width 0.15)
				(type solid)
			)
			(layer "B.Fab")
		)
		(fp_line
			(start -0.5 0.25)
			(end 0.498 0.25)
			(stroke
				(width 0.15)
				(type solid)
			)
			(layer "B.Fab")
		)
		(fp_line
			(start 0.498 -0.248)
			(end -0.5 -0.248)
			(stroke
				(width 0.15)
				(type solid)
			)
			(layer "B.Fab")
		)
		(fp_line
			(start 0.498 0.25)
			(end 0.498 -0.248)
			(stroke
				(width 0.15)
				(type solid)
			)
			(layer "B.Fab")
		)
		(pad "1" smd roundrect
			(at -0.5 0 270)
			(size 0.6 0.6)
			(layers "B.Cu" "B.Mask" "B.Paste")
			(roundrect_rratio 0.25)
			(net 1 "GND")
			(pintype "passive")
		)
		(pad "2" smd roundrect
			(at 0.498 0)
			(size 0.6 0.6)
			(layers "B.Cu" "B.Mask" "B.Paste")
			(roundrect_rratio 0.25)
			(net 227 "+1V0")
			(pintype "passive")
		)
	)
	(footprint "antmicro-footprints:C_0402_1005Metric"
		(layer "B.Cu")
		(at 105.96 171.98 90)
		(descr "Capacitor SMD 0402")
		(tags "capacitor SMD 0402")
		(property "Reference" "C236"
			(at 0 0.699 90)
			(layer "B.SilkS")
			(hide yes)
			(effects
				(font
					(size 0.7 0.7)
					(thickness 0.15)
				)
				(justify right bottom mirror)
			)
		)
		(property "Value" "C_100n_0402"
			(at -1.022927 -2.155213 90)
			(layer "B.Fab")
			(effects
				(font
					(size 0.7 0.7)
					(thickness 0.15)
				)
				(justify right bottom mirror)
			)
		)
		(property "Datasheet" "https://www.murata.com/products/productdetail?partno=GRM155R61H104KE14%23"
			(at 0 0 90)
			(layer "F.Fab")
			(hide yes)
			(effects
				(font
					(size 1.27 1.27)
					(thickness 0.15)
				)
			)
		)
		(property "Author" "Antmicro"
			(at 277.94 66.02 0)
			(layer "B.Fab")
			(hide yes)
			(effects
				(font
					(size 1 1)
					(thickness 0.15)
				)
				(justify mirror)
			)
		)
		(property "Dielectric" "X5R"
			(at 277.94 66.02 0)
			(layer "B.Fab")
			(hide yes)
			(effects
				(font
					(size 1 1)
					(thickness 0.15)
				)
				(justify mirror)
			)
		)
		(property "License" "Apache-2.0"
			(at 277.94 66.02 0)
			(layer "B.Fab")
			(hide yes)
			(effects
				(font
					(size 1 1)
					(thickness 0.15)
				)
				(justify mirror)
			)
		)
		(property "MPN" "GRM155R61H104KE14D"
			(at 277.94 66.02 0)
			(layer "B.Fab")
			(hide yes)
			(effects
				(font
					(size 1 1)
					(thickness 0.15)
				)
				(justify mirror)
			)
		)
		(property "Manufacturer" "Murata"
			(at 277.94 66.02 0)
			(layer "B.Fab")
			(hide yes)
			(effects
				(font
					(size 1 1)
					(thickness 0.15)
				)
				(justify mirror)
			)
		)
		(property "Val" "100n"
			(at 277.94 66.02 0)
			(layer "B.Fab")
			(hide yes)
			(effects
				(font
					(size 1 1)
					(thickness 0.15)
				)
				(justify mirror)
			)
		)
		(property "Voltage" "50V"
			(at 277.94 66.02 0)
			(layer "B.Fab")
			(hide yes)
			(effects
				(font
					(size 1 1)
					(thickness 0.15)
				)
				(justify mirror)
			)
		)
		(sheetname "/Debug FTDI/")
		(sheetfile "debug-ftdi.kicad_sch")
		(attr smd)
		(fp_rect
			(start -0.925 0.47)
			(end 0.925 -0.47)
			(stroke
				(width 0.05)
				(type default)
			)
			(fill no)
			(layer "B.CrtYd")
		)
		(fp_line
			(start 0.504 -0.248)
			(end -0.494 -0.248)
			(stroke
				(width 0.15)
				(type solid)
			)
			(layer "B.Fab")
		)
		(fp_line
			(start -0.494 -0.248)
			(end -0.494 0.25)
			(stroke
				(width 0.15)
				(type solid)
			)
			(layer "B.Fab")
		)
		(fp_line
			(start 0.504 0.25)
			(end 0.504 -0.248)
			(stroke
				(width 0.15)
				(type solid)
			)
			(layer "B.Fab")
		)
		(fp_line
			(start -0.494 0.25)
			(end 0.504 0.25)
			(stroke
				(width 0.15)
				(type solid)
			)
			(layer "B.Fab")
		)
		(pad "1" smd roundrect
			(at -0.48 0 90)
			(size 0.59 0.64)
			(layers "B.Cu" "B.Mask" "B.Paste")
			(roundrect_rratio 0.25)
			(net 1 "GND")
			(pintype "passive")
		)
		(pad "2" smd roundrect
			(at 0.48 0 90)
			(size 0.59 0.64)
			(layers "B.Cu" "B.Mask" "B.Paste")
			(roundrect_rratio 0.25)
			(net 200 "+3V3")
			(pintype "passive")
		)
	)
	(footprint "antmicro-footprints:TP_SMD_1mm"
		(layer "B.Cu")
		(at 201.8 157.4 -90)
		(property "Reference" "TP39"
			(at -3.45 -0.45 90)
			(layer "B.SilkS")
			(effects
				(font
					(size 0.7 0.7)
					(thickness 0.15)
				)
				(justify left bottom mirror)
			)
		)
		(property "Value" "TP_1mm_SMD"
			(at 0 -1.4 90)
			(layer "B.Fab")
			(effects
				(font
					(size 0.7 0.7)
					(thickness 0.15)
				)
				(justify left bottom mirror)
			)
		)
		(property "MPN" ""
			(at 0 0 90)
			(unlocked yes)
			(layer "B.Fab")
			(hide yes)
			(effects
				(font
					(size 1 1)
					(thickness 0.15)
				)
				(justify mirror)
			)
		)
		(property "Manufacturer" ""
			(at 0 0 90)
			(unlocked yes)
			(layer "B.Fab")
			(hide yes)
			(effects
				(font
					(size 1 1)
					(thickness 0.15)
				)
				(justify mirror)
			)
		)
		(property "Author" "Antmicro"
			(at 0 0 90)
			(unlocked yes)
			(layer "B.Fab")
			(hide yes)
			(effects
				(font
					(size 1 1)
					(thickness 0.15)
				)
				(justify mirror)
			)
		)
		(property "License" "Apache-2.0"
			(at 0 0 90)
			(unlocked yes)
			(layer "B.Fab")
			(hide yes)
			(effects
				(font
					(size 1 1)
					(thickness 0.15)
				)
				(justify mirror)
			)
		)
		(sheetname "/I^{2}C/")
		(sheetfile "i2c.kicad_sch")
		(attr exclude_from_pos_files)
		(fp_circle
			(center 0 0)
			(end 0.6 0)
			(stroke
				(width 0.05)
				(type default)
			)
			(fill no)
			(layer "B.CrtYd")
		)
		(fp_text user "License: Apache-2.0"
			(at -0.5 -5.2 90)
			(layer "B.Fab")
			(effects
				(font
					(size 0.7 0.7)
					(thickness 0.15)
				)
				(justify left bottom mirror)
			)
		)
		(fp_text user "Author: Antmicro"
			(at -0.5 -4 90)
			(layer "B.Fab")
			(effects
				(font
					(size 0.7 0.7)
					(thickness 0.15)
				)
				(justify left bottom mirror)
			)
		)
		(fp_text user "${REFERENCE}"
			(at -0.5 -2.8 90)
			(layer "B.Fab")
			(effects
				(font
					(size 0.7 0.7)
					(thickness 0.15)
				)
				(justify left bottom mirror)
			)
		)
		(pad "1" smd circle
			(at 0 0 270)
			(size 1 1)
			(layers "B.Cu" "B.Mask")
			(net 1 "GND")
			(pinfunction "1")
			(pintype "passive")
		)
	)
)
